(kicad_pcb
	(version 20260206)
	(generator "pcbnew")
	(generator_version "10.0")
	(general
		(thickness 1.6)
		(legacy_teardrops no)
	)
	(paper "A4")
	(title_block
		(title "01162023_DA0F0TEBIF0_F0T_Expander_BD_F_brd_V02_OCP.brd")
		(comment 1 "Grand Teton / footprints 8220-8228 of 9728")
	)
	(layers
		(0 "F.Cu" signal "TOP")
		(4 "In1.Cu" signal "GND")
		(6 "In2.Cu" signal "VCC")
		(8 "In3.Cu" signal "VCC1")
		(10 "In4.Cu" signal "GND1")
		(12 "In5.Cu" signal "IN1")
		(14 "In6.Cu" signal "GND2")
		(16 "In7.Cu" signal "IN2")
		(18 "In8.Cu" signal "GND3")
		(20 "In9.Cu" signal "IN3")
		(22 "In10.Cu" signal "GND4")
		(24 "In11.Cu" signal "IN4")
		(26 "In12.Cu" signal "GND5")
		(28 "In13.Cu" signal "IN5")
		(30 "In14.Cu" signal "GND6")
		(32 "In15.Cu" signal "IN6")
		(34 "In16.Cu" signal "GND7")
		(2 "B.Cu" signal "BOTTOM")
		(9 "F.Adhes" user "F.Adhesive")
		(11 "B.Adhes" user "B.Adhesive")
		(13 "F.Paste" user "Package Geometry/Pastemask Top")
		(15 "B.Paste" user "Package Geometry/Pastemask Bottom")
		(5 "F.SilkS" user "Ref Des/Silkscreen Top")
		(7 "B.SilkS" user "Ref Des/Silkscreen Bottom")
		(1 "F.Mask" user "Board Geometry/Soldermask Top")
		(3 "B.Mask" user "Board Geometry/Soldermask Bottom")
		(17 "Dwgs.User" user "User.Drawings")
		(19 "Cmts.User" user "User.Comments")
		(21 "Eco1.User" user "User.Eco1")
		(23 "Eco2.User" user "User.Eco2")
		(25 "Edge.Cuts" user "Board Geometry/Outline")
		(27 "Margin" user)
		(31 "F.CrtYd" user "Package Geometry/Place Bound Top")
		(29 "B.CrtYd" user "Package Geometry/Place Bound Bottom")
		(35 "F.Fab" user "Ref Des/Assembly Top")
		(33 "B.Fab" user "Ref Des/Assembly Bottom")
	)
	(footprint ""
		(layer "B.Cu")
		(at 288.049716 -303.499774 -90)
		(property "Reference" "C3266"
			(at 0 0 90)
			(layer "B.SilkS")
			(hide yes)
			(effects
				(font
					(size 1.27 1.27)
				)
				(justify mirror)
			)
		)
		(property "Value" ""
			(at 0 0 90)
			(layer "B.Fab")
			(effects
				(font
					(size 1.27 1.27)
				)
				(justify mirror)
			)
		)
		(duplicate_pad_numbers_are_jumpers no)
		(fp_line
			(start -0.299974 0.150114)
			(end 0.299974 0.150114)
			(stroke
				(width 0.1)
				(type default)
			)
			(layer "B.Fab")
		)
		(fp_line
			(start 0.299974 0.150114)
			(end 0.299974 -0.150114)
			(stroke
				(width 0.1)
				(type default)
			)
			(layer "B.Fab")
		)
		(fp_line
			(start -0.299974 -0.150114)
			(end -0.299974 0.150114)
			(stroke
				(width 0.1)
				(type default)
			)
			(layer "B.Fab")
		)
		(fp_line
			(start 0.299974 -0.150114)
			(end -0.299974 -0.150114)
			(stroke
				(width 0.1)
				(type default)
			)
			(layer "B.Fab")
		)
		(pad "1" smd rect
			(at 0.2667 0 90)
			(size 0.3048 0.381)
			(layers "B.Cu" "B.Mask" "B.Paste")
			(net "P1V25_PEX2")
		)
		(pad "2" smd rect
			(at -0.2667 0 90)
			(size 0.3048 0.381)
			(layers "B.Cu" "B.Mask" "B.Paste")
			(net "GND")
		)
	)
	(footprint ""
		(layer "B.Cu")
		(at 179.55006 -299.699934 -90)
		(property "Reference" "C1468"
			(at 0 0 90)
			(layer "B.SilkS")
			(hide yes)
			(effects
				(font
					(size 1.27 1.27)
				)
				(justify mirror)
			)
		)
		(property "Value" ""
			(at 0 0 90)
			(layer "B.Fab")
			(effects
				(font
					(size 1.27 1.27)
				)
				(justify mirror)
			)
		)
		(duplicate_pad_numbers_are_jumpers no)
		(fp_line
			(start -0.299974 0.150114)
			(end 0.299974 0.150114)
			(stroke
				(width 0.1)
				(type default)
			)
			(layer "B.Fab")
		)
		(fp_line
			(start 0.299974 0.150114)
			(end 0.299974 -0.150114)
			(stroke
				(width 0.1)
				(type default)
			)
			(layer "B.Fab")
		)
		(fp_line
			(start -0.299974 -0.150114)
			(end -0.299974 0.150114)
			(stroke
				(width 0.1)
				(type default)
			)
			(layer "B.Fab")
		)
		(fp_line
			(start 0.299974 -0.150114)
			(end -0.299974 -0.150114)
			(stroke
				(width 0.1)
				(type default)
			)
			(layer "B.Fab")
		)
		(pad "1" smd rect
			(at 0.2667 0 90)
			(size 0.3048 0.381)
			(layers "B.Cu" "B.Mask" "B.Paste")
			(net "P0V8_SERDES_VDDA_PEX1")
		)
		(pad "2" smd rect
			(at -0.2667 0 90)
			(size 0.3048 0.381)
			(layers "B.Cu" "B.Mask" "B.Paste")
			(net "GND")
		)
	)
	(footprint ""
		(layer "B.Cu")
		(at 237.631986 -355.200458)
		(property "Reference" "PR7151"
			(at 0 0 0)
			(layer "B.SilkS")
			(hide yes)
			(effects
				(font
					(size 1.27 1.27)
				)
				(justify mirror)
			)
		)
		(property "Value" ""
			(at 0 0 0)
			(layer "B.Fab")
			(effects
				(font
					(size 1.27 1.27)
				)
				(justify mirror)
			)
		)
		(duplicate_pad_numbers_are_jumpers no)
		(fp_line
			(start -0.7874 -0.4064)
			(end -0.7874 0.4064)
			(stroke
				(width 0.1524)
				(type default)
			)
			(layer "B.SilkS")
		)
		(fp_line
			(start -0.7874 0.4064)
			(end 0.7874 0.4064)
			(stroke
				(width 0.1524)
				(type default)
			)
			(layer "B.SilkS")
		)
		(fp_line
			(start 0.7874 -0.4064)
			(end -0.7874 -0.4064)
			(stroke
				(width 0.1524)
				(type default)
			)
			(layer "B.SilkS")
		)
		(fp_line
			(start 0.7874 0.4064)
			(end 0.7874 -0.4064)
			(stroke
				(width 0.1524)
				(type default)
			)
			(layer "B.SilkS")
		)
		(fp_line
			(start -0.67945 -0.3048)
			(end -0.67945 0.3048)
			(stroke
				(width 0.1)
				(type default)
			)
			(layer "B.Fab")
		)
		(fp_line
			(start -0.67945 0.3048)
			(end -0.120396 0.3048)
			(stroke
				(width 0.1)
				(type default)
			)
			(layer "B.Fab")
		)
		(fp_line
			(start -0.12065 -0.3048)
			(end -0.67945 -0.3048)
			(stroke
				(width 0.1)
				(type default)
			)
			(layer "B.Fab")
		)
		(fp_line
			(start -0.12065 -0.2794)
			(end -0.12065 -0.3048)
			(stroke
				(width 0.1)
				(type default)
			)
			(layer "B.Fab")
		)
		(fp_line
			(start -0.120396 0.2794)
			(end 0.12065 0.2794)
			(stroke
				(width 0.1)
				(type default)
			)
			(layer "B.Fab")
		)
		(fp_line
			(start -0.120396 0.3048)
			(end -0.120396 0.2794)
			(stroke
				(width 0.1)
				(type default)
			)
			(layer "B.Fab")
		)
		(fp_line
			(start 0.12065 -0.305054)
			(end 0.12065 -0.2794)
			(stroke
				(width 0.1)
				(type default)
			)
			(layer "B.Fab")
		)
		(fp_line
			(start 0.12065 -0.2794)
			(end -0.12065 -0.2794)
			(stroke
				(width 0.1)
				(type default)
			)
			(layer "B.Fab")
		)
		(fp_line
			(start 0.12065 0.2794)
			(end 0.12065 0.3048)
			(stroke
				(width 0.1)
				(type default)
			)
			(layer "B.Fab")
		)
		(fp_line
			(start 0.12065 0.3048)
			(end 0.67945 0.3048)
			(stroke
				(width 0.1)
				(type default)
			)
			(layer "B.Fab")
		)
		(fp_line
			(start 0.67945 -0.305054)
			(end 0.12065 -0.305054)
			(stroke
				(width 0.1)
				(type default)
			)
			(layer "B.Fab")
		)
		(fp_line
			(start 0.67945 0.3048)
			(end 0.67945 -0.305054)
			(stroke
				(width 0.1)
				(type default)
			)
			(layer "B.Fab")
		)
		(pad "1" smd circle
			(at 0.40005 0 180)
			(size 0 0)
			(layers "B.Cu" "B.Mask" "B.Paste")
			(net "P12V_HSC_ADC_N")
		)
		(pad "2" smd circle
			(at -0.40005 0 180)
			(size 0 0)
			(layers "B.Cu" "B.Mask" "B.Paste")
			(net "P12V_HSC_SENSE2_R2_N")
		)
	)
	(footprint ""
		(layer "B.Cu")
		(at 163.874958 -299.491654 90)
		(property "Reference" "C3197"
			(at 0 0 90)
			(layer "B.SilkS")
			(hide yes)
			(effects
				(font
					(size 1.27 1.27)
				)
				(justify mirror)
			)
		)
		(property "Value" ""
			(at 0 0 90)
			(layer "B.Fab")
			(effects
				(font
					(size 1.27 1.27)
				)
				(justify mirror)
			)
		)
		(duplicate_pad_numbers_are_jumpers no)
		(fp_line
			(start 0.299974 -0.150114)
			(end -0.299974 -0.150114)
			(stroke
				(width 0.1)
				(type default)
			)
			(layer "B.Fab")
		)
		(fp_line
			(start -0.299974 -0.150114)
			(end -0.299974 0.150114)
			(stroke
				(width 0.1)
				(type default)
			)
			(layer "B.Fab")
		)
		(fp_line
			(start 0.299974 0.150114)
			(end 0.299974 -0.150114)
			(stroke
				(width 0.1)
				(type default)
			)
			(layer "B.Fab")
		)
		(fp_line
			(start -0.299974 0.150114)
			(end 0.299974 0.150114)
			(stroke
				(width 0.1)
				(type default)
			)
			(layer "B.Fab")
		)
		(pad "1" smd rect
			(at 0.2667 0 270)
			(size 0.3048 0.381)
			(layers "B.Cu" "B.Mask" "B.Paste")
			(net "PCEPLL0_VDDA18_PEX1")
		)
		(pad "2" smd rect
			(at -0.2667 0 270)
			(size 0.3048 0.381)
			(layers "B.Cu" "B.Mask" "B.Paste")
			(net "GND")
		)
	)
	(footprint ""
		(layer "B.Cu")
		(at 229.349046 -140.173202)
		(property "Reference" "C2793"
			(at 0 0 0)
			(layer "B.SilkS")
			(hide yes)
			(effects
				(font
					(size 1.27 1.27)
				)
				(justify mirror)
			)
		)
		(property "Value" ""
			(at 0 0 0)
			(layer "B.Fab")
			(effects
				(font
					(size 1.27 1.27)
				)
				(justify mirror)
			)
		)
		(duplicate_pad_numbers_are_jumpers no)
		(fp_line
			(start -1.2954 -0.5842)
			(end -1.2954 0.5842)
			(stroke
				(width 0.1524)
				(type default)
			)
			(layer "B.SilkS")
		)
		(fp_line
			(start -1.2954 0.5842)
			(end 1.2954 0.5842)
			(stroke
				(width 0.1524)
				(type default)
			)
			(layer "B.SilkS")
		)
		(fp_line
			(start 1.2954 -0.5842)
			(end -1.2954 -0.5842)
			(stroke
				(width 0.1524)
				(type default)
			)
			(layer "B.SilkS")
		)
		(fp_line
			(start 1.2954 0.5842)
			(end 1.2954 -0.5842)
			(stroke
				(width 0.1524)
				(type default)
			)
			(layer "B.SilkS")
		)
		(fp_line
			(start -1.1938 -0.4064)
			(end -1.1938 0.4064)
			(stroke
				(width 0.1)
				(type default)
			)
			(layer "B.Fab")
		)
		(fp_line
			(start -1.1938 0.4064)
			(end -0.8636 0.4064)
			(stroke
				(width 0.1)
				(type default)
			)
			(layer "B.Fab")
		)
		(fp_line
			(start -0.8636 -0.4572)
			(end -0.8636 -0.4064)
			(stroke
				(width 0.1)
				(type default)
			)
			(layer "B.Fab")
		)
		(fp_line
			(start -0.8636 -0.4064)
			(end -1.1938 -0.4064)
			(stroke
				(width 0.1)
				(type default)
			)
			(layer "B.Fab")
		)
		(fp_line
			(start -0.8636 0.4064)
			(end -0.8636 0.4572)
			(stroke
				(width 0.1)
				(type default)
			)
			(layer "B.Fab")
		)
		(fp_line
			(start -0.8636 0.4572)
			(end 0.8636 0.4572)
			(stroke
				(width 0.1)
				(type default)
			)
			(layer "B.Fab")
		)
		(fp_line
			(start 0.8636 -0.4572)
			(end -0.8636 -0.4572)
			(stroke
				(width 0.1)
				(type default)
			)
			(layer "B.Fab")
		)
		(fp_line
			(start 0.8636 -0.4064)
			(end 0.8636 -0.4572)
			(stroke
				(width 0.1)
				(type default)
			)
			(layer "B.Fab")
		)
		(fp_line
			(start 0.8636 0.4064)
			(end 1.1938 0.4064)
			(stroke
				(width 0.1)
				(type default)
			)
			(layer "B.Fab")
		)
		(fp_line
			(start 0.8636 0.4572)
			(end 0.8636 0.4064)
			(stroke
				(width 0.1)
				(type default)
			)
			(layer "B.Fab")
		)
		(fp_line
			(start 1.1938 -0.4064)
			(end 0.8636 -0.4064)
			(stroke
				(width 0.1)
				(type default)
			)
			(layer "B.Fab")
		)
		(fp_line
			(start 1.1938 0.4064)
			(end 1.1938 -0.4064)
			(stroke
				(width 0.1)
				(type default)
			)
			(layer "B.Fab")
		)
		(pad "1" smd rect
			(at 0.7366 0 270)
			(size 0.7112 0.8128)
			(layers "B.Cu" "B.Mask" "B.Paste")
			(net "P3V3_CLK_GEN_VDDXTAL_CK440_PEX")
		)
		(pad "2" smd rect
			(at -0.7366 0 270)
			(size 0.7112 0.8128)
			(layers "B.Cu" "B.Mask" "B.Paste")
			(net "GND")
		)
	)
	(footprint ""
		(layer "B.Cu")
		(at 290.89985 -288.299906 90)
		(property "Reference" "C3283"
			(at 0 0 90)
			(layer "B.SilkS")
			(hide yes)
			(effects
				(font
					(size 1.27 1.27)
				)
				(justify mirror)
			)
		)
		(property "Value" ""
			(at 0 0 90)
			(layer "B.Fab")
			(effects
				(font
					(size 1.27 1.27)
				)
				(justify mirror)
			)
		)
		(duplicate_pad_numbers_are_jumpers no)
		(fp_line
			(start 0.299974 -0.150114)
			(end -0.299974 -0.150114)
			(stroke
				(width 0.1)
				(type default)
			)
			(layer "B.Fab")
		)
		(fp_line
			(start -0.299974 -0.150114)
			(end -0.299974 0.150114)
			(stroke
				(width 0.1)
				(type default)
			)
			(layer "B.Fab")
		)
		(fp_line
			(start 0.299974 0.150114)
			(end 0.299974 -0.150114)
			(stroke
				(width 0.1)
				(type default)
			)
			(layer "B.Fab")
		)
		(fp_line
			(start -0.299974 0.150114)
			(end 0.299974 0.150114)
			(stroke
				(width 0.1)
				(type default)
			)
			(layer "B.Fab")
		)
		(pad "1" smd rect
			(at 0.2667 0 270)
			(size 0.3048 0.381)
			(layers "B.Cu" "B.Mask" "B.Paste")
			(net "P1V25_PEX2")
		)
		(pad "2" smd rect
			(at -0.2667 0 270)
			(size 0.3048 0.381)
			(layers "B.Cu" "B.Mask" "B.Paste")
			(net "GND")
		)
	)
	(footprint ""
		(layer "B.Cu")
		(at 353.910646 -216.946734)
		(property "Reference" "R5637"
			(at 0 0 0)
			(layer "B.SilkS")
			(hide yes)
			(effects
				(font
					(size 1.27 1.27)
				)
				(justify mirror)
			)
		)
		(property "Value" ""
			(at 0 0 0)
			(layer "B.Fab")
			(effects
				(font
					(size 1.27 1.27)
				)
				(justify mirror)
			)
		)
		(duplicate_pad_numbers_are_jumpers no)
		(fp_line
			(start -1.2954 -0.5842)
			(end -1.2954 0.5842)
			(stroke
				(width 0.1524)
				(type default)
			)
			(layer "B.SilkS")
		)
		(fp_line
			(start -1.2954 0.5842)
			(end 1.2954 0.5842)
			(stroke
				(width 0.1524)
				(type default)
			)
			(layer "B.SilkS")
		)
		(fp_line
			(start 1.2954 -0.5842)
			(end -1.2954 -0.5842)
			(stroke
				(width 0.1524)
				(type default)
			)
			(layer "B.SilkS")
		)
		(fp_line
			(start 1.2954 0.5842)
			(end 1.2954 -0.5842)
			(stroke
				(width 0.1524)
				(type default)
			)
			(layer "B.SilkS")
		)
		(fp_line
			(start -1.1938 -0.406654)
			(end -1.1938 0.4064)
			(stroke
				(width 0.1)
				(type default)
			)
			(layer "B.Fab")
		)
		(fp_line
			(start -1.1938 0.4064)
			(end -0.8636 0.4064)
			(stroke
				(width 0.1)
				(type default)
			)
			(layer "B.Fab")
		)
		(fp_line
			(start -0.8636 -0.4572)
			(end -0.8636 -0.406654)
			(stroke
				(width 0.1)
				(type default)
			)
			(layer "B.Fab")
		)
		(fp_line
			(start -0.8636 -0.406654)
			(end -1.1938 -0.406654)
			(stroke
				(width 0.1)
				(type default)
			)
			(layer "B.Fab")
		)
		(fp_line
			(start -0.8636 0.4064)
			(end -0.8636 0.4572)
			(stroke
				(width 0.1)
				(type default)
			)
			(layer "B.Fab")
		)
		(fp_line
			(start -0.8636 0.4572)
			(end 0.8636 0.4572)
			(stroke
				(width 0.1)
				(type default)
			)
			(layer "B.Fab")
		)
		(fp_line
			(start 0.8636 -0.4572)
			(end -0.8636 -0.4572)
			(stroke
				(width 0.1)
				(type default)
			)
			(layer "B.Fab")
		)
		(fp_line
			(start 0.8636 -0.406654)
			(end 0.8636 -0.4572)
			(stroke
				(width 0.1)
				(type default)
			)
			(layer "B.Fab")
		)
		(fp_line
			(start 0.8636 0.4064)
			(end 1.1938 0.4064)
			(stroke
				(width 0.1)
				(type default)
			)
			(layer "B.Fab")
		)
		(fp_line
			(start 0.8636 0.4318)
			(end 0.8636 0.4064)
			(stroke
				(width 0.1)
				(type default)
			)
			(layer "B.Fab")
		)
		(fp_line
			(start 0.8636 0.4572)
			(end 0.8636 0.4318)
			(stroke
				(width 0.1)
				(type default)
			)
			(layer "B.Fab")
		)
		(fp_line
			(start 1.1938 -0.406654)
			(end 0.8636 -0.406654)
			(stroke
				(width 0.1)
				(type default)
			)
			(layer "B.Fab")
		)
		(fp_line
			(start 1.1938 0.4064)
			(end 1.1938 -0.406654)
			(stroke
				(width 0.1)
				(type default)
			)
			(layer "B.Fab")
		)
		(pad "1" smd rect
			(at 0.7366 0 270)
			(size 0.7112 0.8128)
			(layers "B.Cu" "B.Mask" "B.Paste")
			(net "P3V3_AUX")
		)
		(pad "2" smd rect
			(at -0.7366 0 270)
			(size 0.7112 0.8128)
			(layers "B.Cu" "B.Mask" "B.Paste")
			(net "P3V3_FPGA_VCCIO1")
		)
	)
	(footprint ""
		(layer "B.Cu")
		(at 403.10054 -86.813898 180)
		(property "Reference" "R6270"
			(at 0 0 0)
			(layer "B.SilkS")
			(hide yes)
			(effects
				(font
					(size 1.27 1.27)
				)
				(justify mirror)
			)
		)
		(property "Value" ""
			(at 0 0 0)
			(layer "B.Fab")
			(effects
				(font
					(size 1.27 1.27)
				)
				(justify mirror)
			)
		)
		(duplicate_pad_numbers_are_jumpers no)
		(fp_line
			(start 0.7874 0.4064)
			(end 0.7874 -0.4064)
			(stroke
				(width 0.1524)
				(type default)
			)
			(layer "B.SilkS")
		)
		(fp_line
			(start 0.7874 -0.4064)
			(end -0.7874 -0.4064)
			(stroke
				(width 0.1524)
				(type default)
			)
			(layer "B.SilkS")
		)
		(fp_line
			(start -0.7874 0.4064)
			(end 0.7874 0.4064)
			(stroke
				(width 0.1524)
				(type default)
			)
			(layer "B.SilkS")
		)
		(fp_line
			(start -0.7874 -0.4064)
			(end -0.7874 0.4064)
			(stroke
				(width 0.1524)
				(type default)
			)
			(layer "B.SilkS")
		)
		(fp_line
			(start 0.67945 0.3048)
			(end 0.67945 -0.305054)
			(stroke
				(width 0.1)
				(type default)
			)
			(layer "B.Fab")
		)
		(fp_line
			(start 0.67945 -0.305054)
			(end 0.12065 -0.305054)
			(stroke
				(width 0.1)
				(type default)
			)
			(layer "B.Fab")
		)
		(fp_line
			(start 0.12065 0.3048)
			(end 0.67945 0.3048)
			(stroke
				(width 0.1)
				(type default)
			)
			(layer "B.Fab")
		)
		(fp_line
			(start 0.12065 0.2794)
			(end 0.12065 0.3048)
			(stroke
				(width 0.1)
				(type default)
			)
			(layer "B.Fab")
		)
		(fp_line
			(start 0.12065 -0.2794)
			(end -0.12065 -0.2794)
			(stroke
				(width 0.1)
				(type default)
			)
			(layer "B.Fab")
		)
		(fp_line
			(start 0.12065 -0.305054)
			(end 0.12065 -0.2794)
			(stroke
				(width 0.1)
				(type default)
			)
			(layer "B.Fab")
		)
		(fp_line
			(start -0.120396 0.3048)
			(end -0.120396 0.2794)
			(stroke
				(width 0.1)
				(type default)
			)
			(layer "B.Fab")
		)
		(fp_line
			(start -0.120396 0.2794)
			(end 0.12065 0.2794)
			(stroke
				(width 0.1)
				(type default)
			)
			(layer "B.Fab")
		)
		(fp_line
			(start -0.12065 -0.2794)
			(end -0.12065 -0.3048)
			(stroke
				(width 0.1)
				(type default)
			)
			(layer "B.Fab")
		)
		(fp_line
			(start -0.12065 -0.3048)
			(end -0.67945 -0.3048)
			(stroke
				(width 0.1)
				(type default)
			)
			(layer "B.Fab")
		)
		(fp_line
			(start -0.67945 0.3048)
			(end -0.120396 0.3048)
			(stroke
				(width 0.1)
				(type default)
			)
			(layer "B.Fab")
		)
		(fp_line
			(start -0.67945 -0.3048)
			(end -0.67945 0.3048)
			(stroke
				(width 0.1)
				(type default)
			)
			(layer "B.Fab")
		)
		(pad "1" smd circle
			(at 0.40005 0)
			(size 0 0)
			(layers "B.Cu" "B.Mask" "B.Paste")
			(net "SMB_BIC_I2C6_MUX_CLK_R_SDA")
		)
		(pad "2" smd circle
			(at -0.40005 0)
			(size 0 0)
			(layers "B.Cu" "B.Mask" "B.Paste")
			(net "SMB_CLK_ISO_SDA")
		)
	)
	(footprint ""
		(layer "B.Cu")
		(at 168.150032 -290.199826 90)
		(property "Reference" "C1425"
			(at 0 0 90)
			(layer "B.SilkS")
			(hide yes)
			(effects
				(font
					(size 1.27 1.27)
				)
				(justify mirror)
			)
		)
		(property "Value" ""
			(at 0 0 90)
			(layer "B.Fab")
			(effects
				(font
					(size 1.27 1.27)
				)
				(justify mirror)
			)
		)
		(duplicate_pad_numbers_are_jumpers no)
		(fp_line
			(start 0.299974 -0.150114)
			(end -0.299974 -0.150114)
			(stroke
				(width 0.1)
				(type default)
			)
			(layer "B.Fab")
		)
		(fp_line
			(start -0.299974 -0.150114)
			(end -0.299974 0.150114)
			(stroke
				(width 0.1)
				(type default)
			)
			(layer "B.Fab")
		)
		(fp_line
			(start 0.299974 0.150114)
			(end 0.299974 -0.150114)
			(stroke
				(width 0.1)
				(type default)
			)
			(layer "B.Fab")
		)
		(fp_line
			(start -0.299974 0.150114)
			(end 0.299974 0.150114)
			(stroke
				(width 0.1)
				(type default)
			)
			(layer "B.Fab")
		)
		(pad "1" smd rect
			(at 0.2667 0 270)
			(size 0.3048 0.381)
			(layers "B.Cu" "B.Mask" "B.Paste")
			(net "P0V8_SERDES_VDDA_PEX1")
		)
		(pad "2" smd rect
			(at -0.2667 0 270)
			(size 0.3048 0.381)
			(layers "B.Cu" "B.Mask" "B.Paste")
			(net "GND")
		)
	)
)
